# S9S_MB_2U (Grand Teton) — schematic netlist excerpt (pin names and nets, part order shuffled) for the footprints in the layout excerpt that follows; sources: Cadence DE-HDL packaged netlist, KiCad conversion of 03242023_DA0F0TMBIJ0_F0T_Motherboard_J_brd_V01_OCP.brd

PU75_P1_1  ISL99390FRZTR5935  ISL99390FRZ-TR5935 IC  pkg QFN21_6X5XB  page 289
  VOS  = PVCCFA_EHV_FIVRA_CPU1_VOS1
  AGND  = GND
  VCC  = PVCCFA_EHV_FIVRA_CPU1_VDD1
  PVCC  = PVCCFA_EHV_FIVRA_CPU1_PVCC1
  PGND1  = GND
  GL1  = NC
  PGND2  = GND
  SW  = SW_PVCCFA_EHV_FIVRA_CPU1_SW1
  VIN1  = SW_P12V_PVCCFA_EHV_FIVRA_CPU1_R
  VIN2  = SW_P12V_PVCCFA_EHV_FIVRA_CPU1_R
  DNC  = NC
  PHASE  = SW_PVCCFA_EHV_FIVRA_CPU1_BOOTR1
  BOOT  = SW_PVCCFA_EHV_FIVRA_CPU1_BOOT1
  PWM  = PVCCFA_EHV_FIVRA_CPU1_PWM1
  EN  = PVCCFA_EHV_FIVRA_CPU1_VDD1
  TOUT_FLT  = PVCCFA_EHV_FIVRA_CPU1_BTSEN
  LSET  = PVCCFA_EHV_FIVRA_CPU1_LSET1
  IOUT  = PVCCFA_EHV_FIVRA_CPU1_IMON1
  REFIN  = PVCCIN_CPU1_VREF
  PGND3  = GND
  GL2  = NC

(kicad_pcb
	(version 20260206)
	(generator "pcbnew")
	(generator_version "10.0")
	(general
		(thickness 1.6)
		(legacy_teardrops no)
	)
	(paper "A4")
	(title_block
		(title "03242023_DA0F0TMBIJ0_F0T_Motherboard_J_brd_V01_OCP.brd")
		(comment 1 "Grand Teton / footprints 1357-1357 of 6105")
	)
	(layers
		(0 "F.Cu" signal "TOP")
		(4 "In1.Cu" signal "GND")
		(6 "In2.Cu" signal "IN1")
		(8 "In3.Cu" signal "GND1")
		(10 "In4.Cu" signal "IN2")
		(12 "In5.Cu" signal "GND2")
		(14 "In6.Cu" signal "IN3")
		(16 "In7.Cu" signal "GND3")
		(18 "In8.Cu" signal "VCC")
		(20 "In9.Cu" signal "VCC1")
		(22 "In10.Cu" signal "GND4")
		(24 "In11.Cu" signal "IN4")
		(26 "In12.Cu" signal "GND5")
		(28 "In13.Cu" signal "IN5")
		(30 "In14.Cu" signal "GND6")
		(32 "In15.Cu" signal "IN6")
		(34 "In16.Cu" signal "GND7")
		(2 "B.Cu" signal "BOTTOM")
		(9 "F.Adhes" user "F.Adhesive")
		(11 "B.Adhes" user "B.Adhesive")
		(13 "F.Paste" user "Package Geometry/Pastemask Top")
		(15 "B.Paste" user "Package Geometry/Pastemask Bottom")
		(5 "F.SilkS" user "Ref Des/Silkscreen Top")
		(7 "B.SilkS" user "Ref Des/Silkscreen Bottom")
		(1 "F.Mask" user "Board Geometry/Soldermask Top")
		(3 "B.Mask" user "Board Geometry/Soldermask Bottom")
		(17 "Dwgs.User" user "User.Drawings")
		(19 "Cmts.User" user "User.Comments")
		(21 "Eco1.User" user "User.Eco1")
		(23 "Eco2.User" user "User.Eco2")
		(25 "Edge.Cuts" user "Board Geometry/Outline")
		(27 "Margin" user)
		(31 "F.CrtYd" user "Package Geometry/Place Bound Top")
		(29 "B.CrtYd" user "Package Geometry/Place Bound Bottom")
		(35 "F.Fab" user "Ref Des/Assembly Top")
		(33 "B.Fab" user "Ref Des/Assembly Bottom")
	)
	(footprint ""
		(layer "F.Cu")
		(at 172.024294 -353.554284)
		(property "Reference" "PU75_P1_1"
			(at -2.245614 -6.277356 0)
			(unlocked yes)
			(layer "F.SilkS")
			(effects
				(font
					(size 0.7874 0.5842)
					(thickness 0.1524)
				)
				(justify left)
			)
		)
		(property "Value" ""
			(at 0 0 0)
			(layer "F.Fab")
			(effects
				(font
					(size 1.27 1.27)
				)
			)
		)
		(duplicate_pad_numbers_are_jumpers no)
		(fp_line
			(start -2.500122 -2.999994)
			(end -2.24409 -2.999994)
			(stroke
				(width 0.1524)
				(type default)
			)
			(layer "F.SilkS")
		)
		(fp_line
			(start -2.500122 -2.529078)
			(end -2.500122 -2.999994)
			(stroke
				(width 0.1524)
				(type default)
			)
			(layer "F.SilkS")
		)
		(fp_line
			(start -2.500122 0.6604)
			(end -2.500122 0.229108)
			(stroke
				(width 0.1524)
				(type default)
			)
			(layer "F.SilkS")
		)
		(fp_line
			(start -2.500122 2.999994)
			(end -2.500122 2.339594)
			(stroke
				(width 0.1524)
				(type default)
			)
			(layer "F.SilkS")
		)
		(fp_line
			(start -2.2987 2.999994)
			(end -2.500122 2.999994)
			(stroke
				(width 0.1524)
				(type default)
			)
			(layer "F.SilkS")
		)
		(fp_line
			(start 2.31394 -2.999994)
			(end 2.500122 -2.999994)
			(stroke
				(width 0.1524)
				(type default)
			)
			(layer "F.SilkS")
		)
		(fp_line
			(start 2.500122 -2.999994)
			(end 2.500122 -2.44348)
			(stroke
				(width 0.1524)
				(type default)
			)
			(layer "F.SilkS")
		)
		(fp_line
			(start 2.500122 2.339594)
			(end 2.500122 2.999994)
			(stroke
				(width 0.1524)
				(type default)
			)
			(layer "F.SilkS")
		)
		(fp_line
			(start 2.500122 2.999994)
			(end 2.2987 2.999994)
			(stroke
				(width 0.1524)
				(type default)
			)
			(layer "F.SilkS")
		)
		(fp_poly
			(pts
				(xy -5.275072 -2.780538) (xy -4.259072 -2.272538) (xy -5.275072 -1.764538)
			)
			(stroke
				(width 0)
				(type default)
			)
			(fill yes)
			(layer "F.SilkS")
		)
		(fp_line
			(start -2.500122 -2.999994)
			(end 2.500122 -2.999994)
			(stroke
				(width 0.1)
				(type default)
			)
			(layer "F.Fab")
		)
		(fp_line
			(start -2.500122 2.999994)
			(end -2.500122 -2.999994)
			(stroke
				(width 0.1)
				(type default)
			)
			(layer "F.Fab")
		)
		(fp_line
			(start 2.500122 -2.999994)
			(end 2.500122 2.999994)
			(stroke
				(width 0.1)
				(type default)
			)
			(layer "F.Fab")
		)
		(fp_line
			(start 2.500122 2.999994)
			(end -2.500122 2.999994)
			(stroke
				(width 0.1)
				(type default)
			)
			(layer "F.Fab")
		)
		(fp_poly
			(pts
				(xy -4.218432 -2.783078) (xy -4.218432 -1.767078) (xy -3.202432 -2.275078)
			)
			(stroke
				(width 0)
				(type default)
			)
			(fill yes)
			(layer "F.Fab")
		)
		(pad "1" smd rect
			(at -2.400046 -2.275078 90)
			(size 0.2286 0.6096)
			(layers "F.Cu" "F.Mask" "F.Paste")
			(net "PVCCFA_EHV_FIVRA_CPU1_VOS1")
		)
		(pad "2" smd rect
			(at -2.400046 -1.82499 90)
			(size 0.2286 0.6096)
			(layers "F.Cu" "F.Mask" "F.Paste")
			(net "GND")
		)
		(pad "3" smd rect
			(at -2.400046 -1.374902 90)
			(size 0.2286 0.6096)
			(layers "F.Cu" "F.Mask" "F.Paste")
			(net "PVCCFA_EHV_FIVRA_CPU1_VDD1")
		)
		(pad "4" smd rect
			(at -2.400046 -0.925068 90)
			(size 0.2286 0.6096)
			(layers "F.Cu" "F.Mask" "F.Paste")
			(net "PVCCFA_EHV_FIVRA_CPU1_PVCC1")
		)
		(pad "5" smd rect
			(at -2.400046 -0.47498 90)
			(size 0.2286 0.6096)
			(layers "F.Cu" "F.Mask" "F.Paste")
			(net "GND")
		)
		(pad "6" smd rect
			(at -2.400046 -0.024892 90)
			(size 0.2286 0.6096)
			(layers "F.Cu" "F.Mask" "F.Paste")
			(net "Net_8505")
		)
		(pad "7_9-20_24" smd circle
			(at 0 1.150112 90)
			(size 0 0)
			(layers "F.Cu" "F.Mask" "F.Paste")
			(net "GND")
		)
		(pad "10_19" smd rect
			(at 0 2.899918 90)
			(size 0.6096 4.318)
			(layers "F.Cu" "F.Mask" "F.Paste")
			(net "SW_PVCCFA_EHV_FIVRA_CPU1_SW1")
		)
		(pad "25_29" smd rect
			(at 1.549908 -1.279906 270)
			(size 2.0574 2.3114)
			(layers "F.Cu" "F.Mask" "F.Paste")
			(net "SW_P12V_PVCCFA_EHV_FIVRA_CPU1_R")
		)
		(pad "30" smd rect
			(at 2.05994 -2.899918)
			(size 0.2286 0.6096)
			(layers "F.Cu" "F.Mask" "F.Paste")
			(net "SW_P12V_PVCCFA_EHV_FIVRA_CPU1_R")
		)
		(pad "31" smd rect
			(at 1.610106 -2.899918)
			(size 0.2286 0.6096)
			(layers "F.Cu" "F.Mask" "F.Paste")
			(net "Net_8506")
		)
		(pad "32" smd rect
			(at 1.160018 -2.899918)
			(size 0.2286 0.6096)
			(layers "F.Cu" "F.Mask" "F.Paste")
			(net "SW_PVCCFA_EHV_FIVRA_CPU1_BOOTR1")
		)
		(pad "33" smd rect
			(at 0.70993 -2.899918)
			(size 0.2286 0.6096)
			(layers "F.Cu" "F.Mask" "F.Paste")
			(net "SW_PVCCFA_EHV_FIVRA_CPU1_BOOT1")
		)
		(pad "34" smd rect
			(at 0.260096 -2.899918)
			(size 0.2286 0.6096)
			(layers "F.Cu" "F.Mask" "F.Paste")
			(net "PVCCFA_EHV_FIVRA_CPU1_PWM1")
		)
		(pad "35" smd rect
			(at -0.189992 -2.899918)
			(size 0.2286 0.6096)
			(layers "F.Cu" "F.Mask" "F.Paste")
			(net "PVCCFA_EHV_FIVRA_CPU1_VDD1")
		)
		(pad "36" smd rect
			(at -0.64008 -2.899918)
			(size 0.2286 0.6096)
			(layers "F.Cu" "F.Mask" "F.Paste")
			(net "PVCCFA_EHV_FIVRA_CPU1_BTSEN")
		)
		(pad "37" smd rect
			(at -1.089914 -2.899918)
			(size 0.2286 0.6096)
			(layers "F.Cu" "F.Mask" "F.Paste")
			(net "PVCCFA_EHV_FIVRA_CPU1_LSET1")
		)
		(pad "38" smd rect
			(at -1.540002 -2.899918)
			(size 0.2286 0.6096)
			(layers "F.Cu" "F.Mask" "F.Paste")
			(net "PVCCFA_EHV_FIVRA_CPU1_IMON1")
		)
		(pad "39" smd rect
			(at -1.99009 -2.899918)
			(size 0.2286 0.6096)
			(layers "F.Cu" "F.Mask" "F.Paste")
			(net "PVCCIN_CPU1_VREF")
		)
		(pad "40" smd rect
			(at -0.87503 -1.27508)
			(size 1.7526 1.9558)
			(layers "F.Cu" "F.Mask" "F.Paste")
			(net "GND")
		)
		(pad "41" smd rect
			(at -1.525016 0.249936 270)
			(size 0.3048 0.4572)
			(layers "F.Cu" "F.Mask" "F.Paste")
			(net "Net_8504")
		)
		(zone
			(layer "F.Cu")
			(hatch none 0.5)
			(connect_pads
				(clearance 0)
			)
			(min_thickness 0.25)
			(keepout
				(tracks not_allowed)
				(vias allowed)
				(pads allowed)
				(copperpour not_allowed)
				(footprints allowed)
			)
			(placement
				(enabled no)
				(sheetname "")
			)
			(fill
				(thermal_gap 0.5)
				(thermal_bridge_width 0.5)
				(island_removal_mode 0)
			)
			(polygon
				(pts
					(xy 169.524172 -350.55429) (xy 169.524172 -351.285048) (xy 174.524416 -351.285048) (xy 174.524416 -350.55429)
					(xy 174.234094 -350.55429) (xy 174.234094 -351.009966) (xy 169.814494 -351.009966) (xy 169.814494 -350.55429)
				)
			)
		)
		(zone
			(layer "F.Cu")
			(hatch none 0.5)
			(connect_pads
				(clearance 0)
			)
			(min_thickness 0.25)
			(keepout
				(tracks not_allowed)
				(vias allowed)
				(pads allowed)
				(copperpour not_allowed)
				(footprints allowed)
			)
			(placement
				(enabled no)
				(sheetname "")
			)
			(fill
				(thermal_gap 0.5)
				(thermal_bridge_width 0.5)
				(island_removal_mode 0)
			)
			(polygon
				(pts
					(xy 170.26636 -353.800664) (xy 171.03344 -353.800664) (xy 171.03344 -353.471988) (xy 171.073572 -353.471988)
					(xy 171.073572 -352.859848) (xy 171.018708 -352.804984) (xy 169.524172 -352.804984) (xy 169.524172 -353.261676)
					(xy 170.219878 -353.261676) (xy 170.219878 -353.101148) (xy 170.778678 -353.101148) (xy 170.778678 -353.507548)
					(xy 170.219878 -353.507548) (xy 170.219878 -353.287076) (xy 169.524172 -353.287076) (xy 169.524172 -353.414076)
					(xy 169.979848 -353.414076) (xy 169.979848 -353.786948) (xy 170.26636 -353.786948)
				)
			)
		)
	)
)
